# S9S_MB_2U (Grand Teton) — schematic netlist excerpt (pin names and nets, part order shuffled) for the footprints in the layout excerpt that follows; sources: Cadence DE-HDL packaged netlist, KiCad conversion of 03242023_DA0F0TMBIJ0_F0T_Motherboard_J_brd_V01_OCP.brd

J14  SCONN288_ADR50017P087CC  SCONN288_ADR50017-P087CC IO  pkg DDR288S_1-1VXB  page 95
  VIN_BULK0  = P12V_S3_AUX_CPU0_NVDIMM
  RFU0  = TP_CHG_CPU0_DIMM2_FRU_0
  VIN_MGMT  = P3V3_AUX
  HSCL  = I3C_SPD_DDREFGH_CPU0_LVC1_SCL_5
  HSDA  = I3C_SPD_DDREFGH_CPU0_LVC1_SDA
  VSS0  = GND
  DQ0_A  = M_G_CPU0_SA_DQ<0>
  VSS1  = GND
  DQ1_A  = M_G_CPU0_SA_DQ<1>
  VSS2  = GND
  DQS0_A_T  = M_G_CPU0_SA_DQS_DP<0>
  DQS0_A_C  = M_G_CPU0_SA_DQS_DN<0>
  VSS3  = GND
  DQ4_A  = M_G_CPU0_SA_DQ<4>
  VSS4  = GND
  DQ5_A  = M_G_CPU0_SA_DQ<5>
  VSS5  = GND
  DQ8_A  = M_G_CPU0_SA_DQ<8>
  VSS6  = GND
  DQ9_A  = M_G_CPU0_SA_DQ<9>
  VSS7  = GND
  DQS1_A_T  = M_G_CPU0_SA_DQS_DP<1>
  DQS1_A_C  = M_G_CPU0_SA_DQS_DN<1>
  VSS8  = GND
  DQ12_A  = M_G_CPU0_SA_DQ<12>
  VSS9  = GND
  DQ13_A  = M_G_CPU0_SA_DQ<13>
  VSS10  = GND
  DQ16_A  = M_G_CPU0_SA_DQ<16>
  VSS11  = GND
  DQ17_A  = M_G_CPU0_SA_DQ<17>
  VSS12  = GND
  DQS2_A_T  = M_G_CPU0_SA_DQS_DP<2>
  DQS2_A_C  = M_G_CPU0_SA_DQS_DN<2>
  VSS13  = GND
  DQ20_A  = M_G_CPU0_SA_DQ<20>
  VSS14  = GND
  DQ21_A  = M_G_CPU0_SA_DQ<21>
  VSS15  = GND
  DQ24_A  = M_G_CPU0_SA_DQ<24>
  VSS16  = GND
  DQ25_A  = M_G_CPU0_SA_DQ<25>
  VSS17  = GND
  DQS3_A_T  = M_G_CPU0_SA_DQS_DP<3>
  DQS3_A_C  = M_G_CPU0_SA_DQS_DN<3>
  VSS18  = GND
  DQ28_A  = M_G_CPU0_SA_DQ<28>
  VSS19  = GND
  DQ29_A  = M_G_CPU0_SA_DQ<29>
  VSS20  = GND
  CB0_A  = M_G_CPU0_SA_CB<0>
  VSS21  = GND
  CB1_A  = M_G_CPU0_SA_CB<1>
  VSS22  = GND
  DQS4_A_T  = M_G_CPU0_SA_DQS_DP<4>
  DQS4_A_C  = M_G_CPU0_SA_DQS_DN<4>
  VSS23  = GND
  CB4_A  = M_G_CPU0_SA_CB<4>
  VSS24  = GND
  CB5_A  = M_G_CPU0_SA_CB<5>
  VSS25  = GND
  ALERT_N  = M_G_CPU0_ALERT_N
  VSS26  = GND
  CS0_A_N  = M_G_CPU0_SA_CS_N<2>
  VSS27  = GND
  CA0_A  = M_G_CPU0_SA_CA<0>
  VSS28  = GND
  CA2_A  = M_G_CPU0_SA_CA<2>
  VSS29  = GND
  CA4_A  = M_G_CPU0_SA_CA<4>
  VSS30  = GND
  CA6_A  = M_G_CPU0_SA_CA<6>
  VSS31  = GND
  PAR_A  = M_G_CPU0_SA_PAR
  VSS32  = GND
  CA0_B  = M_G_CPU0_SB_CA<0>
  VSS33  = GND
  CA2_B  = M_G_CPU0_SB_CA<2>
  VSS34  = GND
  CA4_B  = M_G_CPU0_SB_CA<4>
  VSS35  = GND
  CA6_B  = M_G_CPU0_SB_CA<6>
  VSS36  = GND
  CS0_B_N  = M_G_CPU0_SB_CS_N<2>
  VSS37  = GND
  \lbd||rsp_a_n\  = M_G_CPU0_SA_RSP<1>
  \lbs||rsp_b_n\  = M_G_CPU0_SB_RSP<1>
  VSS38  = GND
  CB4_B  = M_G_CPU0_SB_CB<4>
  VSS39  = GND
  CB5_B  = M_G_CPU0_SB_CB<5>
  VSS40  = GND
  \dqs9_b_t||tdqs9_b_t||dbi4_b_n\  = M_G_CPU0_SB_DQS_DP<9>
  \dqs9_b_c||tdqs9_b_c\  = M_G_CPU0_SB_DQS_DN<9>
  VSS41  = GND
  CB0_B  = M_G_CPU0_SB_CB<0>
  VSS42  = GND
  CB1_B  = M_G_CPU0_SB_CB<1>
  VSS43  = GND
  DQ0_B  = M_G_CPU0_SB_DQ<0>
  VSS44  = GND
  DQ1_B  = M_G_CPU0_SB_DQ<1>
  VSS45  = GND
  DQS0_B_T  = M_G_CPU0_SB_DQS_DP<0>
  DQS0_B_C  = M_G_CPU0_SB_DQS_DN<0>
  VSS46  = GND
  DQ4_B  = M_G_CPU0_SB_DQ<4>
  VSS47  = GND
  DQ5_B  = M_G_CPU0_SB_DQ<5>
  VSS48  = GND
  DQ8_B  = M_G_CPU0_SB_DQ<8>
  VSS49  = GND
  DQ9_B  = M_G_CPU0_SB_DQ<9>
  VSS50  = GND
  DQS1_B_T  = M_G_CPU0_SB_DQS_DP<1>
  DQS1_B_C  = M_G_CPU0_SB_DQS_DN<1>
  VSS51  = GND
  DQ12_B  = M_G_CPU0_SB_DQ<12>
  VSS52  = GND
  DQ13_B  = M_G_CPU0_SB_DQ<13>
  VSS53  = GND
  DQ16_B  = M_G_CPU0_SB_DQ<16>
  VSS54  = GND
  DQ17_B  = M_G_CPU0_SB_DQ<17>
  VSS55  = GND
  DQS2_B_T  = M_G_CPU0_SB_DQS_DP<2>
  DQS2_B_C  = M_G_CPU0_SB_DQS_DN<2>
  VSS56  = GND
  DQ20_B  = M_G_CPU0_SB_DQ<20>
  VSS57  = GND
  DQ21_B  = M_G_CPU0_SB_DQ<21>
  VSS58  = GND
  DQ24_B  = M_G_CPU0_SB_DQ<24>
  VSS59  = GND
  DQ25_B  = M_G_CPU0_SB_DQ<25>
  VSS60  = GND
  DQS3_B_T  = M_G_CPU0_SB_DQS_DP<3>
  DQS3_B_C  = M_G_CPU0_SB_DQS_DN<3>
  VSS61  = GND
  DQ28_B  = M_G_CPU0_SB_DQ<28>
  VSS62  = GND
  DQ29_B  = M_G_CPU0_SB_DQ<29>
  VSS63  = GND
  RFU1  = TP_CHG_CPU0_DIMM2_FRU_1
  VIN_BULK1  = P12V_S3_AUX_CPU0_NVDIMM
  VIN_BULK2  = P12V_S3_AUX_CPU0_NVDIMM
  \pwr_good||fail_n\  = PWRGD_CHG_CPU0_DIMM2
  HSA  = PD_CHG_CPU0_DIMM2_SAA
  RFU2  = TP_CHG_CPU0_DIMM2_FRU_2
  RFU3  = TP_CHG_CPU0_DIMM2_FRU_3
  VSS64  = GND
  DQ2_A  = M_G_CPU0_SA_DQ<2>
  VSS65  = GND
  DQ3_A  = M_G_CPU0_SA_DQ<3>
  VSS66  = GND
  \dqs5_a_c||tdqs5_a_c||dqs5_a_t||tdqs5_a_t\  = M_G_CPU0_SA_DQS_DN<5>
  \dqs5_a_t||tdqs5_a_t\  = M_G_CPU0_SA_DQS_DP<5>
  VSS67  = GND
  DQ6_A  = M_G_CPU0_SA_DQ<6>
  VSS68  = GND
  DQ7_A  = M_G_CPU0_SA_DQ<7>
  VSS69  = GND
  DQ10_A  = M_G_CPU0_SA_DQ<10>
  VSS70  = GND
  DQ11_A  = M_G_CPU0_SA_DQ<11>
  VSS71  = GND
  \dqs6_a_c||tdqs6_a_c||dqs6_a_t||tdqs6_a_t\  = M_G_CPU0_SA_DQS_DN<6>
  \dqs6_a_t||tdqs6_a_t\  = M_G_CPU0_SA_DQS_DP<6>
  VSS72  = GND
  DQ14_A  = M_G_CPU0_SA_DQ<14>
  VSS73  = GND
  DQ15_A  = M_G_CPU0_SA_DQ<15>
  VSS74  = GND
  DQ18_A  = M_G_CPU0_SA_DQ<18>
  VSS75  = GND
  DQ19_A  = M_G_CPU0_SA_DQ<19>
  VSS76  = GND
  \dqs7_a_c||tdqs7_a_c\  = M_G_CPU0_SA_DQS_DN<7>
  \dqs7_a_t||tdqs7_a_t\  = M_G_CPU0_SA_DQS_DP<7>
  VSS77  = GND
  DQ22_A  = M_G_CPU0_SA_DQ<22>
  VSS78  = GND
  DQ23_A  = M_G_CPU0_SA_DQ<23>
  VSS79  = GND
  DQ26_A  = M_G_CPU0_SA_DQ<26>
  VSS80  = GND
  DQ27_A  = M_G_CPU0_SA_DQ<27>
  VSS81  = GND
  \dqs8_a_c||tdqs8_a_c\  = M_G_CPU0_SA_DQS_DN<8>
  \dqs8_a_t||tdqs8_a_t\  = M_G_CPU0_SA_DQS_DP<8>
  VSS82  = GND
  DQ30_A  = M_G_CPU0_SA_DQ<30>
  VSS83  = GND
  DQ31_A  = M_G_CPU0_SA_DQ<31>
  VSS84  = GND
  CB2_A  = M_G_CPU0_SA_CB<2>
  VSS85  = GND
  CB3_A  = M_G_CPU0_SA_CB<3>
  VSS86  = GND
  \dqs9_a_c||tdqs9_a_c\  = M_G_CPU0_SA_DQS_DN<9>
  \dqs9_a_t||tdqs9_a_t\  = M_G_CPU0_SA_DQS_DP<9>
  VSS87  = GND
  CB6_A  = M_G_CPU0_SA_CB<6>
  VSS88  = GND
  CB7_A  = M_G_CPU0_SA_CB<7>
  VSS89  = GND
  RESET_N  = RST_M_GH_CPU0_FPGA_N
  VSS90  = GND
  CS1_A_N  = M_G_CPU0_SA_CS_N<3>
  VSS91  = GND
  CA1_A  = M_G_CPU0_SA_CA<1>
  VSS92  = GND
  CA3_A  = M_G_CPU0_SA_CA<3>
  VSS93  = GND
  CA5_A  = M_G_CPU0_SA_CA<5>
  VSS94  = GND
  CK_T  = M_G_CPU0_CLK_DP<1>
  CK_C  = M_G_CPU0_CLK_DN<1>
  VSS95  = GND
  RFU4  = TP_CHG_CPU0_DIMM2_FRU_4
  CA1_B  = M_G_CPU0_SB_CA<1>
  VSS96  = GND
  CA3_B  = M_G_CPU0_SB_CA<3>
  VSS97  = GND
  CA5_B  = M_G_CPU0_SB_CA<5>
  VSS98  = GND
  PAR_B  = M_G_CPU0_SB_PAR
  VSS99  = GND
  CS1_B_N  = M_G_CPU0_SB_CS_N<3>
  VSS100  = GND
  RFU5  = TP_CHG_CPU0_DIMM2_FRU_5
  RFU6  = TP_CHG_CPU0_DIMM2_FRU_6
  VSS101  = GND
  CB6_B  = M_G_CPU0_SB_CB<6>
  VSS102  = GND
  CB7_B  = M_G_CPU0_SB_CB<7>
  VSS103  = GND
  DQS4_B_C  = M_G_CPU0_SB_DQS_DN<4>
  DQS4_B_T  = M_G_CPU0_SB_DQS_DP<4>
  VSS104  = GND
  CB2_B  = M_G_CPU0_SB_CB<2>
  VSS105  = GND
  CB3_B  = M_G_CPU0_SB_CB<3>
  VSS106  = GND
  DQ2_B  = M_G_CPU0_SB_DQ<2>
  VSS107  = GND
  DQ3_B  = M_G_CPU0_SB_DQ<3>
  VSS108  = GND
  \dqs5_b_c||tdqs5_b_c\  = M_G_CPU0_SB_DQS_DN<5>
  \dqs5_b_t||tdqs5_b_t\  = M_G_CPU0_SB_DQS_DP<5>
  VSS109  = GND
  DQ6_B  = M_G_CPU0_SB_DQ<6>
  VSS110  = GND
  DQ7_B  = M_G_CPU0_SB_DQ<7>
  VSS111  = GND
  DQ10_B  = M_G_CPU0_SB_DQ<10>
  VSS112  = GND
  DQ11_B  = M_G_CPU0_SB_DQ<11>
  VSS113  = GND
  \dqs6_b_c||tdqs6_b_c\  = M_G_CPU0_SB_DQS_DN<6>
  \dqs6_b_t||tdqs6_b_t\  = M_G_CPU0_SB_DQS_DP<6>
  VSS114  = GND
  DQ14_B  = M_G_CPU0_SB_DQ<14>
  VSS115  = GND
  DQ15_B  = M_G_CPU0_SB_DQ<15>
  VSS116  = GND
  DQ18_B  = M_G_CPU0_SB_DQ<18>
  VSS117  = GND
  DQ19_B  = M_G_CPU0_SB_DQ<19>
  VSS118  = GND
  \dqs7_b_c||tdqs7_b_c\  = M_G_CPU0_SB_DQS_DN<7>
  \dqs7_b_t||tdqs7_b_t\  = M_G_CPU0_SB_DQS_DP<7>
  VSS119  = GND
  DQ22_B  = M_G_CPU0_SB_DQ<22>
  VSS120  = GND
  DQ23_B  = M_G_CPU0_SB_DQ<23>
  VSS121  = GND
  DQ26_B  = M_G_CPU0_SB_DQ<26>
  VSS122  = GND
  DQ27_B  = M_G_CPU0_SB_DQ<27>
  VSS123  = GND
  \dqs8_b_c||tdqs8_b_c\  = M_G_CPU0_SB_DQS_DN<8>
  \dqs8_b_t||tdqs8_b_t\  = M_G_CPU0_SB_DQS_DP<8>
  VSS124  = GND
  DQ30_B  = M_G_CPU0_SB_DQ<30>
  VSS125  = GND
  DQ31_B  = M_G_CPU0_SB_DQ<31>
  VSS126  = GND
  G1  = GND
  G2  = GND
  G3  = GND

(kicad_pcb
	(version 20260206)
	(generator "pcbnew")
	(generator_version "10.0")
	(general
		(thickness 1.6)
		(legacy_teardrops no)
	)
	(paper "A4")
	(title_block
		(title "03242023_DA0F0TMBIJ0_F0T_Motherboard_J_brd_V01_OCP.brd")
		(comment 1 "Grand Teton / footprint 3833 of 6105 (J14), pads 229-274 of 291")
	)
	(layers
		(0 "F.Cu" signal "TOP")
		(4 "In1.Cu" signal "GND")
		(6 "In2.Cu" signal "IN1")
		(8 "In3.Cu" signal "GND1")
		(10 "In4.Cu" signal "IN2")
		(12 "In5.Cu" signal "GND2")
		(14 "In6.Cu" signal "IN3")
		(16 "In7.Cu" signal "GND3")
		(18 "In8.Cu" signal "VCC")
		(20 "In9.Cu" signal "VCC1")
		(22 "In10.Cu" signal "GND4")
		(24 "In11.Cu" signal "IN4")
		(26 "In12.Cu" signal "GND5")
		(28 "In13.Cu" signal "IN5")
		(30 "In14.Cu" signal "GND6")
		(32 "In15.Cu" signal "IN6")
		(34 "In16.Cu" signal "GND7")
		(2 "B.Cu" signal "BOTTOM")
		(9 "F.Adhes" user "F.Adhesive")
		(11 "B.Adhes" user "B.Adhesive")
		(13 "F.Paste" user "Package Geometry/Pastemask Top")
		(15 "B.Paste" user "Package Geometry/Pastemask Bottom")
		(5 "F.SilkS" user "Ref Des/Silkscreen Top")
		(7 "B.SilkS" user "Ref Des/Silkscreen Bottom")
		(1 "F.Mask" user "Board Geometry/Soldermask Top")
		(3 "B.Mask" user "Board Geometry/Soldermask Bottom")
		(17 "Dwgs.User" user "User.Drawings")
		(19 "Cmts.User" user "User.Comments")
		(21 "Eco1.User" user "User.Eco1")
		(23 "Eco2.User" user "User.Eco2")
		(25 "Edge.Cuts" user "Board Geometry/Outline")
		(27 "Margin" user)
		(31 "F.CrtYd" user "Package Geometry/Place Bound Top")
		(29 "B.CrtYd" user "Package Geometry/Place Bound Bottom")
		(35 "F.Fab" user "Ref Des/Assembly Top")
		(33 "B.Fab" user "Ref Des/Assembly Bottom")
	)
	(footprint ""
		(layer "F.Cu")
		(at 438.978548 -258.091686)
		(property "Reference" "J14"
			(at -3.683 -81.702148 0)
			(unlocked yes)
			(layer "F.SilkS")
			(effects
				(font
					(size 0.7874 0.5842)
					(thickness 0.1524)
				)
				(justify left)
			)
		)
		(property "Value" ""
			(at 0 0 0)
			(layer "F.Fab")
			(effects
				(font
					(size 1.27 1.27)
				)
			)
		)
		(duplicate_pad_numbers_are_jumpers no)
		(pad "229" smd rect
			(at 2.050034 13.17498 270)
			(size 0.519938 1.4986)
			(layers "F.Cu" "F.Mask" "F.Paste")
			(net "M_G_CPU0_SB_CS_N<3>")
		)
		(pad "230" smd rect
			(at 2.050034 14.025118 270)
			(size 0.519938 1.4986)
			(layers "F.Cu" "F.Mask" "F.Paste")
			(net "GND")
		)
		(pad "231" smd rect
			(at 2.050034 14.875002 270)
			(size 0.519938 1.4986)
			(layers "F.Cu" "F.Mask" "F.Paste")
			(net "TP_CHG_CPU0_DIMM2_FRU_5")
		)
		(pad "232" smd rect
			(at 2.050034 15.724886 270)
			(size 0.519938 1.4986)
			(layers "F.Cu" "F.Mask" "F.Paste")
			(net "TP_CHG_CPU0_DIMM2_FRU_6")
		)
		(pad "233" smd rect
			(at 2.050034 16.575024 270)
			(size 0.519938 1.4986)
			(layers "F.Cu" "F.Mask" "F.Paste")
			(net "GND")
		)
		(pad "234" smd rect
			(at 2.050034 17.424908 270)
			(size 0.519938 1.4986)
			(layers "F.Cu" "F.Mask" "F.Paste")
			(net "M_G_CPU0_SB_CB<6>")
		)
		(pad "235" smd rect
			(at 2.050034 18.275046 270)
			(size 0.519938 1.4986)
			(layers "F.Cu" "F.Mask" "F.Paste")
			(net "GND")
		)
		(pad "236" smd rect
			(at 2.050034 19.12493 270)
			(size 0.519938 1.4986)
			(layers "F.Cu" "F.Mask" "F.Paste")
			(net "M_G_CPU0_SB_CB<7>")
		)
		(pad "237" smd rect
			(at 2.050034 19.975068 270)
			(size 0.519938 1.4986)
			(layers "F.Cu" "F.Mask" "F.Paste")
			(net "GND")
		)
		(pad "238" smd rect
			(at 2.050034 20.824952 270)
			(size 0.519938 1.4986)
			(layers "F.Cu" "F.Mask" "F.Paste")
			(net "M_G_CPU0_SB_DQS_DN<4>")
		)
		(pad "239" smd rect
			(at 2.050034 21.67509 270)
			(size 0.519938 1.4986)
			(layers "F.Cu" "F.Mask" "F.Paste")
			(net "M_G_CPU0_SB_DQS_DP<4>")
		)
		(pad "240" smd rect
			(at 2.050034 22.524974 270)
			(size 0.519938 1.4986)
			(layers "F.Cu" "F.Mask" "F.Paste")
			(net "GND")
		)
		(pad "241" smd rect
			(at 2.050034 23.375112 270)
			(size 0.519938 1.4986)
			(layers "F.Cu" "F.Mask" "F.Paste")
			(net "M_G_CPU0_SB_CB<2>")
		)
		(pad "242" smd rect
			(at 2.050034 24.224996 270)
			(size 0.519938 1.4986)
			(layers "F.Cu" "F.Mask" "F.Paste")
			(net "GND")
		)
		(pad "243" smd rect
			(at 2.050034 25.07488 270)
			(size 0.519938 1.4986)
			(layers "F.Cu" "F.Mask" "F.Paste")
			(net "M_G_CPU0_SB_CB<3>")
		)
		(pad "244" smd rect
			(at 2.050034 25.925018 270)
			(size 0.519938 1.4986)
			(layers "F.Cu" "F.Mask" "F.Paste")
			(net "GND")
		)
		(pad "245" smd rect
			(at 2.050034 26.774902 270)
			(size 0.519938 1.4986)
			(layers "F.Cu" "F.Mask" "F.Paste")
			(net "M_G_CPU0_SB_DQ<2>")
		)
		(pad "246" smd rect
			(at 2.050034 27.62504 270)
			(size 0.519938 1.4986)
			(layers "F.Cu" "F.Mask" "F.Paste")
			(net "GND")
		)
		(pad "247" smd rect
			(at 2.050034 28.474924 270)
			(size 0.519938 1.4986)
			(layers "F.Cu" "F.Mask" "F.Paste")
			(net "M_G_CPU0_SB_DQ<3>")
		)
		(pad "248" smd rect
			(at 2.050034 29.325062 270)
			(size 0.519938 1.4986)
			(layers "F.Cu" "F.Mask" "F.Paste")
			(net "GND")
		)
		(pad "249" smd rect
			(at 2.050034 30.174946 270)
			(size 0.519938 1.4986)
			(layers "F.Cu" "F.Mask" "F.Paste")
			(net "M_G_CPU0_SB_DQS_DN<5>")
		)
		(pad "250" smd rect
			(at 2.050034 31.025084 270)
			(size 0.519938 1.4986)
			(layers "F.Cu" "F.Mask" "F.Paste")
			(net "M_G_CPU0_SB_DQS_DP<5>")
		)
		(pad "251" smd rect
			(at 2.050034 31.874968 270)
			(size 0.519938 1.4986)
			(layers "F.Cu" "F.Mask" "F.Paste")
			(net "GND")
		)
		(pad "252" smd rect
			(at 2.050034 32.725106 270)
			(size 0.519938 1.4986)
			(layers "F.Cu" "F.Mask" "F.Paste")
			(net "M_G_CPU0_SB_DQ<6>")
		)
		(pad "253" smd rect
			(at 2.050034 33.57499 270)
			(size 0.519938 1.4986)
			(layers "F.Cu" "F.Mask" "F.Paste")
			(net "GND")
		)
		(pad "254" smd rect
			(at 2.050034 34.425128 270)
			(size 0.519938 1.4986)
			(layers "F.Cu" "F.Mask" "F.Paste")
			(net "M_G_CPU0_SB_DQ<7>")
		)
		(pad "255" smd rect
			(at 2.050034 35.275012 270)
			(size 0.519938 1.4986)
			(layers "F.Cu" "F.Mask" "F.Paste")
			(net "GND")
		)
		(pad "256" smd rect
			(at 2.050034 36.124896 270)
			(size 0.519938 1.4986)
			(layers "F.Cu" "F.Mask" "F.Paste")
			(net "M_G_CPU0_SB_DQ<10>")
		)
		(pad "257" smd rect
			(at 2.050034 36.975034 270)
			(size 0.519938 1.4986)
			(layers "F.Cu" "F.Mask" "F.Paste")
			(net "GND")
		)
		(pad "258" smd rect
			(at 2.050034 37.824918 270)
			(size 0.519938 1.4986)
			(layers "F.Cu" "F.Mask" "F.Paste")
			(net "M_G_CPU0_SB_DQ<11>")
		)
		(pad "259" smd rect
			(at 2.050034 38.675056 270)
			(size 0.519938 1.4986)
			(layers "F.Cu" "F.Mask" "F.Paste")
			(net "GND")
		)
		(pad "260" smd rect
			(at 2.050034 39.52494 270)
			(size 0.519938 1.4986)
			(layers "F.Cu" "F.Mask" "F.Paste")
			(net "M_G_CPU0_SB_DQS_DN<6>")
		)
		(pad "261" smd rect
			(at 2.050034 40.375078 270)
			(size 0.519938 1.4986)
			(layers "F.Cu" "F.Mask" "F.Paste")
			(net "M_G_CPU0_SB_DQS_DP<6>")
		)
		(pad "262" smd rect
			(at 2.050034 41.224962 270)
			(size 0.519938 1.4986)
			(layers "F.Cu" "F.Mask" "F.Paste")
			(net "GND")
		)
		(pad "263" smd rect
			(at 2.050034 42.0751 270)
			(size 0.519938 1.4986)
			(layers "F.Cu" "F.Mask" "F.Paste")
			(net "M_G_CPU0_SB_DQ<14>")
		)
		(pad "264" smd rect
			(at 2.050034 42.924984 270)
			(size 0.519938 1.4986)
			(layers "F.Cu" "F.Mask" "F.Paste")
			(net "GND")
		)
		(pad "265" smd rect
			(at 2.050034 43.775122 270)
			(size 0.519938 1.4986)
			(layers "F.Cu" "F.Mask" "F.Paste")
			(net "M_G_CPU0_SB_DQ<15>")
		)
		(pad "266" smd rect
			(at 2.050034 44.625006 270)
			(size 0.519938 1.4986)
			(layers "F.Cu" "F.Mask" "F.Paste")
			(net "GND")
		)
		(pad "267" smd rect
			(at 2.050034 45.47489 270)
			(size 0.519938 1.4986)
			(layers "F.Cu" "F.Mask" "F.Paste")
			(net "M_G_CPU0_SB_DQ<18>")
		)
		(pad "268" smd rect
			(at 2.050034 46.325028 270)
			(size 0.519938 1.4986)
			(layers "F.Cu" "F.Mask" "F.Paste")
			(net "GND")
		)
		(pad "269" smd rect
			(at 2.050034 47.174912 270)
			(size 0.519938 1.4986)
			(layers "F.Cu" "F.Mask" "F.Paste")
			(net "M_G_CPU0_SB_DQ<19>")
		)
		(pad "270" smd rect
			(at 2.050034 48.02505 270)
			(size 0.519938 1.4986)
			(layers "F.Cu" "F.Mask" "F.Paste")
			(net "GND")
		)
		(pad "271" smd rect
			(at 2.050034 48.874934 270)
			(size 0.519938 1.4986)
			(layers "F.Cu" "F.Mask" "F.Paste")
			(net "M_G_CPU0_SB_DQS_DN<7>")
		)
		(pad "272" smd rect
			(at 2.050034 49.725072 270)
			(size 0.519938 1.4986)
			(layers "F.Cu" "F.Mask" "F.Paste")
			(net "M_G_CPU0_SB_DQS_DP<7>")
		)
		(pad "273" smd rect
			(at 2.050034 50.574956 270)
			(size 0.519938 1.4986)
			(layers "F.Cu" "F.Mask" "F.Paste")
			(net "GND")
		)
		(pad "274" smd rect
			(at 2.050034 51.425094 270)
			(size 0.519938 1.4986)
			(layers "F.Cu" "F.Mask" "F.Paste")
			(net "M_G_CPU0_SB_DQ<22>")
		)
	)
)
